# BASEBOARD_FAB2 (Tioga Pass) — schematic netlist excerpt (pin names and nets, part order shuffled) for the footprints in the layout excerpt that follows; sources: Cadence DE-HDL packaged netlist, KiCad conversion of Wiwynn_Tioga_Pass_MB.brd

R6P18  RES  0.0 5% CHIP  pkg 0402  page 201 : A = FM_PVCCIN_PVCCSA_CPU0_EN_LVC1 ; B = VR_PVCCIN_CPU0_VREN
R7W2  RES  10.0K 1% EMPTY  pkg 0402  page 166 : A = PECI_CPU_G ; B = GND
R9B10  RES  49.9 1% CHIP  pkg 0402  page 113 : A = JTAG_MCP_TCK ; B = JTAG_MCP_TCK_R1

(kicad_pcb
	(version 20260206)
	(generator "pcbnew")
	(generator_version "10.0")
	(general
		(thickness 1.6)
		(legacy_teardrops no)
	)
	(paper "A4")
	(title_block
		(title "Wiwynn_Tioga_Pass_MB.brd")
		(comment 1 "Tioga Pass / footprints 4628-4630 of 4770")
	)
	(layers
		(0 "F.Cu" signal "TOP")
		(4 "In1.Cu" signal "L2GND")
		(6 "In2.Cu" signal "L3")
		(8 "In3.Cu" signal "L4GND")
		(10 "In4.Cu" signal "L5")
		(12 "In5.Cu" signal "L6GND")
		(14 "In6.Cu" signal "L7VCC")
		(16 "In7.Cu" signal "L8VCC")
		(18 "In8.Cu" signal "L9GND")
		(20 "In9.Cu" signal "L10")
		(22 "In10.Cu" signal "L11GND")
		(24 "In11.Cu" signal "L12")
		(26 "In12.Cu" signal "L13GND")
		(2 "B.Cu" signal "BOTTOM")
		(9 "F.Adhes" user "F.Adhesive")
		(11 "B.Adhes" user "B.Adhesive")
		(13 "F.Paste" user "Package Geometry/Pastemask Top")
		(15 "B.Paste" user "Package Geometry/Pastemask Bottom")
		(5 "F.SilkS" user "Ref Des/Silkscreen Top")
		(7 "B.SilkS" user "Ref Des/Silkscreen Bottom")
		(1 "F.Mask" user "Board Geometry/Soldermask Top")
		(3 "B.Mask" user "Board Geometry/Soldermask Bottom")
		(17 "Dwgs.User" user "User.Drawings")
		(19 "Cmts.User" user "User.Comments")
		(21 "Eco1.User" user "User.Eco1")
		(23 "Eco2.User" user "User.Eco2")
		(25 "Edge.Cuts" user "Board Geometry/Outline")
		(27 "Margin" user)
		(31 "F.CrtYd" user "Package Geometry/Place Bound Top")
		(29 "B.CrtYd" user "Package Geometry/Place Bound Bottom")
		(35 "F.Fab" user "Ref Des/Assembly Top")
		(33 "B.Fab" user "Ref Des/Assembly Bottom")
	)
	(footprint ""
		(layer "B.Cu")
		(at 378.587 -81.8896 -90)
		(property "Reference" "R7W2"
			(at 0.8382 -0.67818 270)
			(unlocked yes)
			(layer "B.SilkS")
			(effects
				(font
					(size 0.4064 0.254)
					(thickness 0.1524)
				)
				(justify left mirror)
			)
		)
		(property "Value" ""
			(at 0 0 90)
			(layer "B.Fab")
			(effects
				(font
					(size 1.27 1.27)
				)
				(justify mirror)
			)
		)
		(duplicate_pad_numbers_are_jumpers no)
		(fp_poly
			(pts
				(xy 0.2794 -0.1016) (xy -0.2794 -0.1016) (xy -0.2794 0.9906) (xy 0.2794 0.9906)
			)
			(stroke
				(width 0)
				(type default)
			)
			(fill no)
			(layer "B.CrtYd")
		)
		(fp_line
			(start -0.2794 0.9906)
			(end -0.2794 -0.1016)
			(stroke
				(width 0.1)
				(type default)
			)
			(layer "B.Fab")
		)
		(fp_line
			(start 0.2794 0.9906)
			(end -0.2794 0.9906)
			(stroke
				(width 0.1)
				(type default)
			)
			(layer "B.Fab")
		)
		(fp_line
			(start -0.2794 -0.1016)
			(end 0.2794 -0.1016)
			(stroke
				(width 0.1)
				(type default)
			)
			(layer "B.Fab")
		)
		(fp_line
			(start 0.2794 -0.1016)
			(end 0.2794 0.9906)
			(stroke
				(width 0.1)
				(type default)
			)
			(layer "B.Fab")
		)
		(pad "1" smd rect
			(at 0 0 90)
			(size 0.508 0.508)
			(layers "B.Cu" "B.Mask" "B.Paste")
			(net "PECI_CPU_G")
		)
		(pad "2" smd rect
			(at 0 0.889 90)
			(size 0.508 0.508)
			(layers "B.Cu" "B.Mask" "B.Paste")
			(net "GND")
		)
		(zone
			(layer "B.Cu")
			(hatch none 0.5)
			(connect_pads
				(clearance 0)
			)
			(min_thickness 0.25)
			(keepout
				(tracks not_allowed)
				(vias allowed)
				(pads allowed)
				(copperpour not_allowed)
				(footprints allowed)
			)
			(placement
				(enabled no)
				(sheetname "")
			)
			(fill
				(thermal_gap 0.5)
				(thermal_bridge_width 0.5)
				(island_removal_mode 0)
			)
			(polygon
				(pts
					(xy 377.952 -81.6356) (xy 377.952 -82.1436) (xy 378.333 -82.1436) (xy 378.333 -81.6356)
				)
			)
		)
		(zone
			(layer "B.Cu")
			(hatch none 0.5)
			(connect_pads
				(clearance 0)
			)
			(min_thickness 0.25)
			(keepout
				(tracks allowed)
				(vias not_allowed)
				(pads allowed)
				(copperpour not_allowed)
				(footprints allowed)
			)
			(placement
				(enabled no)
				(sheetname "")
			)
			(fill
				(thermal_gap 0.5)
				(thermal_bridge_width 0.5)
				(island_removal_mode 0)
			)
			(polygon
				(pts
					(xy 378.333 -81.6356) (xy 378.333 -82.1436) (xy 377.952 -82.1436) (xy 377.952 -81.6356)
				)
			)
		)
	)
	(footprint ""
		(layer "B.Cu")
		(at 464.4644 -134.366 180)
		(property "Reference" "R9B10"
			(at 0 0 0)
			(layer "B.SilkS")
			(hide yes)
			(effects
				(font
					(size 1.27 1.27)
				)
				(justify mirror)
			)
		)
		(property "Value" ""
			(at 0 0 0)
			(layer "B.Fab")
			(effects
				(font
					(size 1.27 1.27)
				)
				(justify mirror)
			)
		)
		(duplicate_pad_numbers_are_jumpers no)
		(fp_poly
			(pts
				(xy 0.2794 -0.1016) (xy -0.2794 -0.1016) (xy -0.2794 0.9906) (xy 0.2794 0.9906)
			)
			(stroke
				(width 0)
				(type default)
			)
			(fill no)
			(layer "B.CrtYd")
		)
		(fp_line
			(start 0.2794 0.9906)
			(end -0.2794 0.9906)
			(stroke
				(width 0.1)
				(type default)
			)
			(layer "B.Fab")
		)
		(fp_line
			(start 0.2794 -0.1016)
			(end 0.2794 0.9906)
			(stroke
				(width 0.1)
				(type default)
			)
			(layer "B.Fab")
		)
		(fp_line
			(start -0.2794 0.9906)
			(end -0.2794 -0.1016)
			(stroke
				(width 0.1)
				(type default)
			)
			(layer "B.Fab")
		)
		(fp_line
			(start -0.2794 -0.1016)
			(end 0.2794 -0.1016)
			(stroke
				(width 0.1)
				(type default)
			)
			(layer "B.Fab")
		)
		(pad "1" smd rect
			(at 0 0)
			(size 0.508 0.508)
			(layers "B.Cu" "B.Mask" "B.Paste")
			(net "JTAG_MCP_TCK")
		)
		(pad "2" smd rect
			(at 0 0.889)
			(size 0.508 0.508)
			(layers "B.Cu" "B.Mask" "B.Paste")
			(net "JTAG_MCP_TCK_R1")
		)
		(zone
			(layer "B.Cu")
			(hatch none 0.5)
			(connect_pads
				(clearance 0)
			)
			(min_thickness 0.25)
			(keepout
				(tracks not_allowed)
				(vias allowed)
				(pads allowed)
				(copperpour not_allowed)
				(footprints allowed)
			)
			(placement
				(enabled no)
				(sheetname "")
			)
			(fill
				(thermal_gap 0.5)
				(thermal_bridge_width 0.5)
				(island_removal_mode 0)
			)
			(polygon
				(pts
					(xy 464.2104 -135.001) (xy 464.7184 -135.001) (xy 464.7184 -134.62) (xy 464.2104 -134.62)
				)
			)
		)
		(zone
			(layer "B.Cu")
			(hatch none 0.5)
			(connect_pads
				(clearance 0)
			)
			(min_thickness 0.25)
			(keepout
				(tracks allowed)
				(vias not_allowed)
				(pads allowed)
				(copperpour not_allowed)
				(footprints allowed)
			)
			(placement
				(enabled no)
				(sheetname "")
			)
			(fill
				(thermal_gap 0.5)
				(thermal_bridge_width 0.5)
				(island_removal_mode 0)
			)
			(polygon
				(pts
					(xy 464.2104 -134.62) (xy 464.7184 -134.62) (xy 464.7184 -135.001) (xy 464.2104 -135.001)
				)
			)
		)
	)
	(footprint ""
		(layer "B.Cu")
		(at 180.1114 -76.2254 90)
		(property "Reference" "R6P18"
			(at 0 0 90)
			(layer "B.SilkS")
			(hide yes)
			(effects
				(font
					(size 1.27 1.27)
				)
				(justify mirror)
			)
		)
		(property "Value" ""
			(at 0 0 90)
			(layer "B.Fab")
			(effects
				(font
					(size 1.27 1.27)
				)
				(justify mirror)
			)
		)
		(duplicate_pad_numbers_are_jumpers no)
		(fp_poly
			(pts
				(xy 0.2794 -0.1016) (xy -0.2794 -0.1016) (xy -0.2794 0.9906) (xy 0.2794 0.9906)
			)
			(stroke
				(width 0)
				(type default)
			)
			(fill no)
			(layer "B.CrtYd")
		)
		(fp_line
			(start 0.2794 -0.1016)
			(end 0.2794 0.9906)
			(stroke
				(width 0.1)
				(type default)
			)
			(layer "B.Fab")
		)
		(fp_line
			(start -0.2794 -0.1016)
			(end 0.2794 -0.1016)
			(stroke
				(width 0.1)
				(type default)
			)
			(layer "B.Fab")
		)
		(fp_line
			(start 0.2794 0.9906)
			(end -0.2794 0.9906)
			(stroke
				(width 0.1)
				(type default)
			)
			(layer "B.Fab")
		)
		(fp_line
			(start -0.2794 0.9906)
			(end -0.2794 -0.1016)
			(stroke
				(width 0.1)
				(type default)
			)
			(layer "B.Fab")
		)
		(pad "1" smd rect
			(at 0 0 270)
			(size 0.508 0.508)
			(layers "B.Cu" "B.Mask" "B.Paste")
			(net "FM_PVCCIN_PVCCSA_CPU0_EN_LVC1")
		)
		(pad "2" smd rect
			(at 0 0.889 270)
			(size 0.508 0.508)
			(layers "B.Cu" "B.Mask" "B.Paste")
			(net "VR_PVCCIN_CPU0_VREN")
		)
		(zone
			(layer "B.Cu")
			(hatch none 0.5)
			(connect_pads
				(clearance 0)
			)
			(min_thickness 0.25)
			(keepout
				(tracks allowed)
				(vias not_allowed)
				(pads allowed)
				(copperpour not_allowed)
				(footprints allowed)
			)
			(placement
				(enabled no)
				(sheetname "")
			)
			(fill
				(thermal_gap 0.5)
				(thermal_bridge_width 0.5)
				(island_removal_mode 0)
			)
			(polygon
				(pts
					(xy 180.3654 -76.4794) (xy 180.3654 -75.9714) (xy 180.7464 -75.9714) (xy 180.7464 -76.4794)
				)
			)
		)
		(zone
			(layer "B.Cu")
			(hatch none 0.5)
			(connect_pads
				(clearance 0)
			)
			(min_thickness 0.25)
			(keepout
				(tracks not_allowed)
				(vias allowed)
				(pads allowed)
				(copperpour not_allowed)
				(footprints allowed)
			)
			(placement
				(enabled no)
				(sheetname "")
			)
			(fill
				(thermal_gap 0.5)
				(thermal_bridge_width 0.5)
				(island_removal_mode 0)
			)
			(polygon
				(pts
					(xy 180.7464 -76.4794) (xy 180.7464 -75.9714) (xy 180.3654 -75.9714) (xy 180.3654 -76.4794)
				)
			)
		)
	)
)
